# TIMECARD (Time Appliance Project (Time Card)) — schematic netlist excerpt (pin names and nets, part order shuffled) for the footprints in the layout excerpt that follows; sources: Cadence DE-HDL packaged netlist, KiCad conversion of R4006-B0001-02_R01.brd

C210  CAPACITOR  0.1UF 10V 10%  pkg SMC_0402R_H022  page 14 : \1\ = XP3R3V_FPGA ; \2\ = SG
R132  RESISTOR  100OHM 1%  pkg SMC_0402R_H016  page 24 : \1\ = R_FT4232_CHD_RX ; \2\ = FT4232_CHD_RX

(kicad_pcb
	(version 20260206)
	(generator "pcbnew")
	(generator_version "10.0")
	(general
		(thickness 1.6)
		(legacy_teardrops no)
	)
	(paper "A4")
	(title_block
		(title "timecard-production-celestica-r4006 — R4006-B0001-02_R01.brd")
		(comment 1 "Time Appliance Project (Time Card) / footprints 1025-1026 of 1113")
	)
	(layers
		(0 "F.Cu" signal "TOP")
		(4 "In1.Cu" signal "L02_GND1")
		(6 "In2.Cu" signal "L03_SIG1")
		(8 "In3.Cu" signal "L04_GND2")
		(10 "In4.Cu" signal "L05_VCC1")
		(12 "In5.Cu" signal "L06_VCC2")
		(14 "In6.Cu" signal "L07_GND3")
		(16 "In7.Cu" signal "L08_SIG2")
		(18 "In8.Cu" signal "L09_GND4")
		(2 "B.Cu" signal "BOTTOM")
		(9 "F.Adhes" user "F.Adhesive")
		(11 "B.Adhes" user "B.Adhesive")
		(13 "F.Paste" user "Package Geometry/Pastemask Top")
		(15 "B.Paste" user "Package Geometry/Pastemask Bottom")
		(5 "F.SilkS" user "Ref Des/Silkscreen Top")
		(7 "B.SilkS" user "Ref Des/Silkscreen Bottom")
		(1 "F.Mask" user "Board Geometry/Soldermask Top")
		(3 "B.Mask" user "Board Geometry/Soldermask Bottom")
		(17 "Dwgs.User" user "User.Drawings")
		(19 "Cmts.User" user "User.Comments")
		(21 "Eco1.User" user "User.Eco1")
		(23 "Eco2.User" user "User.Eco2")
		(25 "Edge.Cuts" user "Board Geometry/Outline")
		(27 "Margin" user)
		(31 "F.CrtYd" user "Package Geometry/Place Bound Top")
		(29 "B.CrtYd" user "Package Geometry/Place Bound Bottom")
		(35 "F.Fab" user "Ref Des/Assembly Top")
		(33 "B.Fab" user "Ref Des/Assembly Bottom")
	)
	(footprint ""
		(layer "B.Cu")
		(at 34.544 -83.312 180)
		(property "Reference" "R132"
			(at 0.381 2.37363 0)
			(unlocked yes)
			(layer "B.SilkS")
			(effects
				(font
					(size 0.7874 0.5842)
					(thickness 0.1524)
				)
				(justify mirror)
			)
		)
		(property "Value" "VAL*"
			(at -0.02032 2.13233 180)
			(unlocked yes)
			(layer "B.Fab")
			(hide yes)
			(effects
				(font
					(size 0.7874 0.5842)
					(thickness 0.1524)
				)
				(justify mirror)
			)
		)
		(property "Tolerance" "TOL*"
			(at -0.044704 3.05435 180)
			(unlocked yes)
			(layer "Cmts.User")
			(hide yes)
			(effects
				(font
					(size 0.7874 0.5842)
					(thickness 0.1524)
				)
				(justify mirror)
			)
		)
		(property "User Part Number" "PARTNUM*"
			(at -0.02032 4.024884 180)
			(unlocked yes)
			(layer "Cmts.User")
			(hide yes)
			(effects
				(font
					(size 0.7874 0.5842)
					(thickness 0.1524)
				)
				(justify mirror)
			)
		)
		(property "Device Type" "RESISTOR-G155-11000-01,100OHM,A"
			(at -0.008382 1.210564 180)
			(unlocked yes)
			(layer "B.Fab")
			(hide yes)
			(effects
				(font
					(size 0.7874 0.5842)
					(thickness 0.1524)
				)
				(justify mirror)
			)
		)
		(duplicate_pad_numbers_are_jumpers no)
		(fp_line
			(start 1.143 0.5588)
			(end -1.143 0.5588)
			(stroke
				(width 0.1)
				(type default)
			)
			(layer "B.SilkS")
		)
		(fp_line
			(start 1.143 -0.5588)
			(end 1.143 0.5588)
			(stroke
				(width 0.1)
				(type default)
			)
			(layer "B.SilkS")
		)
		(fp_line
			(start -1.143 0.5588)
			(end -1.143 -0.5588)
			(stroke
				(width 0.1)
				(type default)
			)
			(layer "B.SilkS")
		)
		(fp_line
			(start -1.143 -0.5588)
			(end 1.143 -0.5588)
			(stroke
				(width 0.1)
				(type default)
			)
			(layer "B.SilkS")
		)
		(fp_rect
			(start 1.143 -0.5588)
			(end -1.143 0.5588)
			(stroke
				(width 0)
				(type default)
			)
			(fill no)
			(layer "B.CrtYd")
		)
		(fp_line
			(start 0.508 0.3048)
			(end -0.508 0.3048)
			(stroke
				(width 0.1)
				(type default)
			)
			(layer "B.Fab")
		)
		(fp_line
			(start 0.508 -0.3048)
			(end 0.508 0.3048)
			(stroke
				(width 0.1)
				(type default)
			)
			(layer "B.Fab")
		)
		(fp_line
			(start -0.508 0.3048)
			(end -0.508 -0.3048)
			(stroke
				(width 0.1)
				(type default)
			)
			(layer "B.Fab")
		)
		(fp_line
			(start -0.508 -0.3048)
			(end 0.508 -0.3048)
			(stroke
				(width 0.1)
				(type default)
			)
			(layer "B.Fab")
		)
		(pad "1" smd rect
			(at 0.5334 0)
			(size 0.7112 0.6096)
			(layers "B.Cu" "B.Mask" "B.Paste")
			(net "R_FT4232_CHD_RX")
		)
		(pad "2" smd rect
			(at -0.5334 0)
			(size 0.7112 0.6096)
			(layers "B.Cu" "B.Mask" "B.Paste")
			(net "FT4232_CHD_RX")
		)
		(zone
			(layer "B.Cu")
			(hatch none 0.5)
			(connect_pads
				(clearance 0)
			)
			(min_thickness 0.25)
			(keepout
				(tracks allowed)
				(vias not_allowed)
				(pads allowed)
				(copperpour not_allowed)
				(footprints allowed)
			)
			(placement
				(enabled no)
				(sheetname "")
			)
			(fill
				(thermal_gap 0.5)
				(thermal_bridge_width 0.5)
				(island_removal_mode 0)
			)
			(polygon
				(pts
					(xy 34.4678 -83.0072) (xy 34.6202 -83.0072) (xy 34.6202 -83.6168) (xy 34.4678 -83.6168)
				)
			)
		)
	)
	(footprint ""
		(layer "B.Cu")
		(at 117.346984 -42.82313)
		(property "Reference" "C210"
			(at 4.033266 0.78613 270)
			(unlocked yes)
			(layer "B.SilkS")
			(effects
				(font
					(size 0.635 0.4064)
					(thickness 0.1524)
				)
				(justify mirror)
			)
		)
		(property "Value" "VAL*"
			(at 0 3.718306 0)
			(unlocked yes)
			(layer "B.Fab")
			(hide yes)
			(effects
				(font
					(size 0.7874 0.5842)
					(thickness 0.127)
				)
				(justify mirror)
			)
		)
		(property "Tolerance" "TOL*"
			(at 0 4.861306 0)
			(unlocked yes)
			(layer "Cmts.User")
			(hide yes)
			(effects
				(font
					(size 0.7874 0.5842)
					(thickness 0.127)
				)
				(justify mirror)
			)
		)
		(property "User Part Number" "PARTNUM*"
			(at 0 2.575306 0)
			(unlocked yes)
			(layer "Cmts.User")
			(hide yes)
			(effects
				(font
					(size 0.7874 0.5842)
					(thickness 0.127)
				)
				(justify mirror)
			)
		)
		(property "Device Type" "CAPACITOR-G105-0B104-CK,0.1UF,A"
			(at 0 1.432306 0)
			(unlocked yes)
			(layer "B.Fab")
			(hide yes)
			(effects
				(font
					(size 0.7874 0.5842)
					(thickness 0.127)
				)
				(justify mirror)
			)
		)
		(duplicate_pad_numbers_are_jumpers no)
		(fp_line
			(start -0.970026 -0.4699)
			(end -0.970026 0.4699)
			(stroke
				(width 0.1)
				(type default)
			)
			(layer "B.SilkS")
		)
		(fp_line
			(start -0.970026 0.4699)
			(end 0.970026 0.4699)
			(stroke
				(width 0.1)
				(type default)
			)
			(layer "B.SilkS")
		)
		(fp_line
			(start 0.970026 -0.4699)
			(end -0.970026 -0.4699)
			(stroke
				(width 0.1)
				(type default)
			)
			(layer "B.SilkS")
		)
		(fp_line
			(start 0.970026 0.4699)
			(end 0.970026 -0.4699)
			(stroke
				(width 0.1)
				(type default)
			)
			(layer "B.SilkS")
		)
		(fp_poly
			(pts
				(xy 0.970026 0.4699) (xy -0.970026 0.4699) (xy -0.970026 -0.4699) (xy 0.970026 -0.4699)
			)
			(stroke
				(width 0)
				(type default)
			)
			(fill no)
			(layer "B.CrtYd")
		)
		(fp_line
			(start -0.508 -0.3048)
			(end -0.508 0.3048)
			(stroke
				(width 0.1)
				(type default)
			)
			(layer "B.Fab")
		)
		(fp_line
			(start -0.508 0.3048)
			(end 0.508 0.3048)
			(stroke
				(width 0.1)
				(type default)
			)
			(layer "B.Fab")
		)
		(fp_line
			(start 0.508 -0.3048)
			(end -0.508 -0.3048)
			(stroke
				(width 0.1)
				(type default)
			)
			(layer "B.Fab")
		)
		(fp_line
			(start 0.508 0.3048)
			(end 0.508 -0.3048)
			(stroke
				(width 0.1)
				(type default)
			)
			(layer "B.Fab")
		)
		(pad "1" smd circle
			(at 0.500126 0 180)
			(size 0.635 0.635)
			(layers "B.Cu" "B.Mask" "B.Paste")
			(net "XP3R3V_FPGA")
		)
		(pad "2" smd circle
			(at -0.500126 0 180)
			(size 0.635 0.635)
			(layers "B.Cu" "B.Mask" "B.Paste")
			(net "SG")
		)
	)
)
